(kicad_pcb
	(version 20260206)
	(generator "pcbnew")
	(generator_version "10.0")
	(general
		(thickness 1.6)
		(legacy_teardrops no)
	)
	(paper "A4")
	(title_block
		(title "Wiwynn_Tioga_Pass_MB.brd")
		(comment 1 "Tioga Pass / footprint 437 of 4770 (J1G3), pads 124-243 of 291")
	)
	(layers
		(0 "F.Cu" signal "TOP")
		(4 "In1.Cu" signal "L2GND")
		(6 "In2.Cu" signal "L3")
		(8 "In3.Cu" signal "L4GND")
		(10 "In4.Cu" signal "L5")
		(12 "In5.Cu" signal "L6GND")
		(14 "In6.Cu" signal "L7VCC")
		(16 "In7.Cu" signal "L8VCC")
		(18 "In8.Cu" signal "L9GND")
		(20 "In9.Cu" signal "L10")
		(22 "In10.Cu" signal "L11GND")
		(24 "In11.Cu" signal "L12")
		(26 "In12.Cu" signal "L13GND")
		(2 "B.Cu" signal "BOTTOM")
		(9 "F.Adhes" user "F.Adhesive")
		(11 "B.Adhes" user "B.Adhesive")
		(13 "F.Paste" user "Package Geometry/Pastemask Top")
		(15 "B.Paste" user "Package Geometry/Pastemask Bottom")
		(5 "F.SilkS" user "Ref Des/Silkscreen Top")
		(7 "B.SilkS" user "Ref Des/Silkscreen Bottom")
		(1 "F.Mask" user "Board Geometry/Soldermask Top")
		(3 "B.Mask" user "Board Geometry/Soldermask Bottom")
		(17 "Dwgs.User" user "User.Drawings")
		(19 "Cmts.User" user "User.Comments")
		(21 "Eco1.User" user "User.Eco1")
		(23 "Eco2.User" user "User.Eco2")
		(25 "Edge.Cuts" user "Board Geometry/Outline")
		(27 "Margin" user)
		(31 "F.CrtYd" user "Package Geometry/Place Bound Top")
		(29 "B.CrtYd" user "Package Geometry/Place Bound Bottom")
		(35 "F.Fab" user "Ref Des/Assembly Top")
		(33 "B.Fab" user "Ref Des/Assembly Bottom")
	)
	(footprint ""
		(layer "F.Cu")
		(at 29.699458 3.778758 90)
		(property "Reference" "J1G3"
			(at 7.054088 34.562542 0)
			(unlocked yes)
			(layer "F.SilkS")
			(effects
				(font
					(size 0.7874 0.5842)
					(thickness 0.1524)
				)
				(justify left)
			)
		)
		(property "Value" ""
			(at 0 0 90)
			(layer "F.Fab")
			(effects
				(font
					(size 1.27 1.27)
				)
			)
		)
		(duplicate_pad_numbers_are_jumpers no)
		(pad "121" smd rect
			(at 0 107.100116 90)
			(size 1.8034 0.508)
			(layers "F.Cu" "F.Mask" "F.Paste")
			(net "M_J_DQS_DP<15>")
		)
		(pad "122" smd rect
			(at 0 107.95 90)
			(size 1.8034 0.508)
			(layers "F.Cu" "F.Mask" "F.Paste")
			(net "M_J_DQS_DN<15>")
		)
		(pad "123" smd rect
			(at 0 108.799884 90)
			(size 1.8034 0.508)
			(layers "F.Cu" "F.Mask" "F.Paste")
			(net "GND")
		)
		(pad "124" smd rect
			(at 0 109.650022 90)
			(size 1.8034 0.508)
			(layers "F.Cu" "F.Mask" "F.Paste")
			(net "M_J_DQ<55>")
		)
		(pad "125" smd rect
			(at 0 110.499906 90)
			(size 1.8034 0.508)
			(layers "F.Cu" "F.Mask" "F.Paste")
			(net "GND")
		)
		(pad "126" smd rect
			(at 0 111.350044 90)
			(size 1.8034 0.508)
			(layers "F.Cu" "F.Mask" "F.Paste")
			(net "M_J_DQ<51>")
		)
		(pad "127" smd rect
			(at 0 112.199928 90)
			(size 1.8034 0.508)
			(layers "F.Cu" "F.Mask" "F.Paste")
			(net "GND")
		)
		(pad "128" smd rect
			(at 0 113.050066 90)
			(size 1.8034 0.508)
			(layers "F.Cu" "F.Mask" "F.Paste")
			(net "M_J_DQ<61>")
		)
		(pad "129" smd rect
			(at 0 113.89995 90)
			(size 1.8034 0.508)
			(layers "F.Cu" "F.Mask" "F.Paste")
			(net "GND")
		)
		(pad "130" smd rect
			(at 0 114.750088 90)
			(size 1.8034 0.508)
			(layers "F.Cu" "F.Mask" "F.Paste")
			(net "M_J_DQ<57>")
		)
		(pad "131" smd rect
			(at 0 115.599972 90)
			(size 1.8034 0.508)
			(layers "F.Cu" "F.Mask" "F.Paste")
			(net "GND")
		)
		(pad "132" smd rect
			(at 0 116.45011 90)
			(size 1.8034 0.508)
			(layers "F.Cu" "F.Mask" "F.Paste")
			(net "M_J_DQS_DP<16>")
		)
		(pad "133" smd rect
			(at 0 117.299994 90)
			(size 1.8034 0.508)
			(layers "F.Cu" "F.Mask" "F.Paste")
			(net "M_J_DQS_DN<16>")
		)
		(pad "134" smd rect
			(at 0 118.149878 90)
			(size 1.8034 0.508)
			(layers "F.Cu" "F.Mask" "F.Paste")
			(net "GND")
		)
		(pad "135" smd rect
			(at 0 119.000016 90)
			(size 1.8034 0.508)
			(layers "F.Cu" "F.Mask" "F.Paste")
			(net "M_J_DQ<63>")
		)
		(pad "136" smd rect
			(at 0 119.8499 90)
			(size 1.8034 0.508)
			(layers "F.Cu" "F.Mask" "F.Paste")
			(net "GND")
		)
		(pad "137" smd rect
			(at 0 120.700038 90)
			(size 1.8034 0.508)
			(layers "F.Cu" "F.Mask" "F.Paste")
			(net "M_J_DQ<59>")
		)
		(pad "138" smd rect
			(at 0 121.549922 90)
			(size 1.8034 0.508)
			(layers "F.Cu" "F.Mask" "F.Paste")
			(net "GND")
		)
		(pad "139" smd rect
			(at 0 122.40006 90)
			(size 1.8034 0.508)
			(layers "F.Cu" "F.Mask" "F.Paste")
			(net "GND")
		)
		(pad "140" smd rect
			(at 0 123.249944 90)
			(size 1.8034 0.508)
			(layers "F.Cu" "F.Mask" "F.Paste")
			(net "GND")
		)
		(pad "141" smd rect
			(at 0 124.100082 90)
			(size 1.8034 0.508)
			(layers "F.Cu" "F.Mask" "F.Paste")
			(net "SMB_DDR_GHJ_VPP_SCL")
		)
		(pad "142" smd rect
			(at 0 124.949966 90)
			(size 1.8034 0.508)
			(layers "F.Cu" "F.Mask" "F.Paste")
			(net "PVPP_GHJ")
		)
		(pad "143" smd rect
			(at 0 125.800104 90)
			(size 1.8034 0.508)
			(layers "F.Cu" "F.Mask" "F.Paste")
			(net "PVPP_GHJ")
		)
		(pad "144" smd rect
			(at 0 126.649988 90)
			(size 1.8034 0.508)
			(layers "F.Cu" "F.Mask" "F.Paste")
			(net "TP_CH_J_DIMM_J0_RFU_2")
		)
		(pad "145" smd rect
			(at 4.59994 0 90)
			(size 1.8034 0.508)
			(layers "F.Cu" "F.Mask" "F.Paste")
			(net "P12V_NVDIMM_GHJ")
		)
		(pad "146" smd rect
			(at 4.59994 0.849884 90)
			(size 1.8034 0.508)
			(layers "F.Cu" "F.Mask" "F.Paste")
			(net "M_J_VREF")
		)
		(pad "147" smd rect
			(at 4.59994 1.700022 90)
			(size 1.8034 0.508)
			(layers "F.Cu" "F.Mask" "F.Paste")
			(net "GND")
		)
		(pad "148" smd rect
			(at 4.59994 2.549906 90)
			(size 1.8034 0.508)
			(layers "F.Cu" "F.Mask" "F.Paste")
			(net "M_J_DQ<4>")
		)
		(pad "149" smd rect
			(at 4.59994 3.400044 90)
			(size 1.8034 0.508)
			(layers "F.Cu" "F.Mask" "F.Paste")
			(net "GND")
		)
		(pad "150" smd rect
			(at 4.59994 4.249928 90)
			(size 1.8034 0.508)
			(layers "F.Cu" "F.Mask" "F.Paste")
			(net "M_J_DQ<0>")
		)
		(pad "151" smd rect
			(at 4.59994 5.100066 90)
			(size 1.8034 0.508)
			(layers "F.Cu" "F.Mask" "F.Paste")
			(net "GND")
		)
		(pad "152" smd rect
			(at 4.59994 5.94995 90)
			(size 1.8034 0.508)
			(layers "F.Cu" "F.Mask" "F.Paste")
			(net "M_J_DQS_DN<0>")
		)
		(pad "153" smd rect
			(at 4.59994 6.800088 90)
			(size 1.8034 0.508)
			(layers "F.Cu" "F.Mask" "F.Paste")
			(net "M_J_DQS_DP<0>")
		)
		(pad "154" smd rect
			(at 4.59994 7.649972 90)
			(size 1.8034 0.508)
			(layers "F.Cu" "F.Mask" "F.Paste")
			(net "GND")
		)
		(pad "155" smd rect
			(at 4.59994 8.50011 90)
			(size 1.8034 0.508)
			(layers "F.Cu" "F.Mask" "F.Paste")
			(net "M_J_DQ<6>")
		)
		(pad "156" smd rect
			(at 4.59994 9.349994 90)
			(size 1.8034 0.508)
			(layers "F.Cu" "F.Mask" "F.Paste")
			(net "GND")
		)
		(pad "157" smd rect
			(at 4.59994 10.199878 90)
			(size 1.8034 0.508)
			(layers "F.Cu" "F.Mask" "F.Paste")
			(net "M_J_DQ<2>")
		)
		(pad "158" smd rect
			(at 4.59994 11.050016 90)
			(size 1.8034 0.508)
			(layers "F.Cu" "F.Mask" "F.Paste")
			(net "GND")
		)
		(pad "159" smd rect
			(at 4.59994 11.8999 90)
			(size 1.8034 0.508)
			(layers "F.Cu" "F.Mask" "F.Paste")
			(net "M_J_DQ<12>")
		)
		(pad "160" smd rect
			(at 4.59994 12.750038 90)
			(size 1.8034 0.508)
			(layers "F.Cu" "F.Mask" "F.Paste")
			(net "GND")
		)
		(pad "161" smd rect
			(at 4.59994 13.599922 90)
			(size 1.8034 0.508)
			(layers "F.Cu" "F.Mask" "F.Paste")
			(net "M_J_DQ<8>")
		)
		(pad "162" smd rect
			(at 4.59994 14.45006 90)
			(size 1.8034 0.508)
			(layers "F.Cu" "F.Mask" "F.Paste")
			(net "GND")
		)
		(pad "163" smd rect
			(at 4.59994 15.299944 90)
			(size 1.8034 0.508)
			(layers "F.Cu" "F.Mask" "F.Paste")
			(net "M_J_DQS_DN<1>")
		)
		(pad "164" smd rect
			(at 4.59994 16.150082 90)
			(size 1.8034 0.508)
			(layers "F.Cu" "F.Mask" "F.Paste")
			(net "M_J_DQS_DP<1>")
		)
		(pad "165" smd rect
			(at 4.59994 16.999966 90)
			(size 1.8034 0.508)
			(layers "F.Cu" "F.Mask" "F.Paste")
			(net "GND")
		)
		(pad "166" smd rect
			(at 4.59994 17.850104 90)
			(size 1.8034 0.508)
			(layers "F.Cu" "F.Mask" "F.Paste")
			(net "M_J_DQ<14>")
		)
		(pad "167" smd rect
			(at 4.59994 18.699988 90)
			(size 1.8034 0.508)
			(layers "F.Cu" "F.Mask" "F.Paste")
			(net "GND")
		)
		(pad "168" smd rect
			(at 4.59994 19.550126 90)
			(size 1.8034 0.508)
			(layers "F.Cu" "F.Mask" "F.Paste")
			(net "M_J_DQ<10>")
		)
		(pad "169" smd rect
			(at 4.59994 20.40001 90)
			(size 1.8034 0.508)
			(layers "F.Cu" "F.Mask" "F.Paste")
			(net "GND")
		)
		(pad "170" smd rect
			(at 4.59994 21.249894 90)
			(size 1.8034 0.508)
			(layers "F.Cu" "F.Mask" "F.Paste")
			(net "M_J_DQ<20>")
		)
		(pad "171" smd rect
			(at 4.59994 22.100032 90)
			(size 1.8034 0.508)
			(layers "F.Cu" "F.Mask" "F.Paste")
			(net "GND")
		)
		(pad "172" smd rect
			(at 4.59994 22.949916 90)
			(size 1.8034 0.508)
			(layers "F.Cu" "F.Mask" "F.Paste")
			(net "M_J_DQ<16>")
		)
		(pad "173" smd rect
			(at 4.59994 23.800054 90)
			(size 1.8034 0.508)
			(layers "F.Cu" "F.Mask" "F.Paste")
			(net "GND")
		)
		(pad "174" smd rect
			(at 4.59994 24.649938 90)
			(size 1.8034 0.508)
			(layers "F.Cu" "F.Mask" "F.Paste")
			(net "M_J_DQS_DN<2>")
		)
		(pad "175" smd rect
			(at 4.59994 25.500076 90)
			(size 1.8034 0.508)
			(layers "F.Cu" "F.Mask" "F.Paste")
			(net "M_J_DQS_DP<2>")
		)
		(pad "176" smd rect
			(at 4.59994 26.34996 90)
			(size 1.8034 0.508)
			(layers "F.Cu" "F.Mask" "F.Paste")
			(net "GND")
		)
		(pad "177" smd rect
			(at 4.59994 27.200098 90)
			(size 1.8034 0.508)
			(layers "F.Cu" "F.Mask" "F.Paste")
			(net "M_J_DQ<22>")
		)
		(pad "178" smd rect
			(at 4.59994 28.049982 90)
			(size 1.8034 0.508)
			(layers "F.Cu" "F.Mask" "F.Paste")
			(net "GND")
		)
		(pad "179" smd rect
			(at 4.59994 28.90012 90)
			(size 1.8034 0.508)
			(layers "F.Cu" "F.Mask" "F.Paste")
			(net "M_J_DQ<18>")
		)
		(pad "180" smd rect
			(at 4.59994 29.750004 90)
			(size 1.8034 0.508)
			(layers "F.Cu" "F.Mask" "F.Paste")
			(net "GND")
		)
		(pad "181" smd rect
			(at 4.59994 30.599888 90)
			(size 1.8034 0.508)
			(layers "F.Cu" "F.Mask" "F.Paste")
			(net "M_J_DQ<28>")
		)
		(pad "182" smd rect
			(at 4.59994 31.450026 90)
			(size 1.8034 0.508)
			(layers "F.Cu" "F.Mask" "F.Paste")
			(net "GND")
		)
		(pad "183" smd rect
			(at 4.59994 32.29991 90)
			(size 1.8034 0.508)
			(layers "F.Cu" "F.Mask" "F.Paste")
			(net "M_J_DQ<24>")
		)
		(pad "184" smd rect
			(at 4.59994 33.150048 90)
			(size 1.8034 0.508)
			(layers "F.Cu" "F.Mask" "F.Paste")
			(net "GND")
		)
		(pad "185" smd rect
			(at 4.59994 33.999932 90)
			(size 1.8034 0.508)
			(layers "F.Cu" "F.Mask" "F.Paste")
			(net "M_J_DQS_DN<3>")
		)
		(pad "186" smd rect
			(at 4.59994 34.85007 90)
			(size 1.8034 0.508)
			(layers "F.Cu" "F.Mask" "F.Paste")
			(net "M_J_DQS_DP<3>")
		)
		(pad "187" smd rect
			(at 4.59994 35.699954 90)
			(size 1.8034 0.508)
			(layers "F.Cu" "F.Mask" "F.Paste")
			(net "GND")
		)
		(pad "188" smd rect
			(at 4.59994 36.550092 90)
			(size 1.8034 0.508)
			(layers "F.Cu" "F.Mask" "F.Paste")
			(net "M_J_DQ<30>")
		)
		(pad "189" smd rect
			(at 4.59994 37.399976 90)
			(size 1.8034 0.508)
			(layers "F.Cu" "F.Mask" "F.Paste")
			(net "GND")
		)
		(pad "190" smd rect
			(at 4.59994 38.250114 90)
			(size 1.8034 0.508)
			(layers "F.Cu" "F.Mask" "F.Paste")
			(net "M_J_DQ<26>")
		)
		(pad "191" smd rect
			(at 4.59994 39.099998 90)
			(size 1.8034 0.508)
			(layers "F.Cu" "F.Mask" "F.Paste")
			(net "GND")
		)
		(pad "192" smd rect
			(at 4.59994 39.949882 90)
			(size 1.8034 0.508)
			(layers "F.Cu" "F.Mask" "F.Paste")
			(net "M_J_ECC<4>")
		)
		(pad "193" smd rect
			(at 4.59994 40.80002 90)
			(size 1.8034 0.508)
			(layers "F.Cu" "F.Mask" "F.Paste")
			(net "GND")
		)
		(pad "194" smd rect
			(at 4.59994 41.649904 90)
			(size 1.8034 0.508)
			(layers "F.Cu" "F.Mask" "F.Paste")
			(net "M_J_ECC<0>")
		)
		(pad "195" smd rect
			(at 4.59994 42.500042 90)
			(size 1.8034 0.508)
			(layers "F.Cu" "F.Mask" "F.Paste")
			(net "GND")
		)
		(pad "196" smd rect
			(at 4.59994 43.349926 90)
			(size 1.8034 0.508)
			(layers "F.Cu" "F.Mask" "F.Paste")
			(net "M_J_DQS_DN<8>")
		)
		(pad "197" smd rect
			(at 4.59994 44.200064 90)
			(size 1.8034 0.508)
			(layers "F.Cu" "F.Mask" "F.Paste")
			(net "M_J_DQS_DP<8>")
		)
		(pad "198" smd rect
			(at 4.59994 45.049948 90)
			(size 1.8034 0.508)
			(layers "F.Cu" "F.Mask" "F.Paste")
			(net "GND")
		)
		(pad "199" smd rect
			(at 4.59994 45.900086 90)
			(size 1.8034 0.508)
			(layers "F.Cu" "F.Mask" "F.Paste")
			(net "M_J_ECC<6>")
		)
		(pad "200" smd rect
			(at 4.59994 46.74997 90)
			(size 1.8034 0.508)
			(layers "F.Cu" "F.Mask" "F.Paste")
			(net "GND")
		)
		(pad "201" smd rect
			(at 4.59994 47.600108 90)
			(size 1.8034 0.508)
			(layers "F.Cu" "F.Mask" "F.Paste")
			(net "M_J_ECC<2>")
		)
		(pad "202" smd rect
			(at 4.59994 48.449992 90)
			(size 1.8034 0.508)
			(layers "F.Cu" "F.Mask" "F.Paste")
			(net "GND")
		)
		(pad "203" smd rect
			(at 4.59994 49.299876 90)
			(size 1.8034 0.508)
			(layers "F.Cu" "F.Mask" "F.Paste")
			(net "M_J_CKE<1>")
		)
		(pad "204" smd rect
			(at 4.59994 50.150014 90)
			(size 1.8034 0.508)
			(layers "F.Cu" "F.Mask" "F.Paste")
			(net "PVDDQ_GHJ")
		)
		(pad "205" smd rect
			(at 4.59994 50.999898 90)
			(size 1.8034 0.508)
			(layers "F.Cu" "F.Mask" "F.Paste")
			(net "TP_CH_J_DIMM_J0_RFU_0")
		)
		(pad "206" smd rect
			(at 4.59994 51.850036 90)
			(size 1.8034 0.508)
			(layers "F.Cu" "F.Mask" "F.Paste")
			(net "PVDDQ_GHJ")
		)
		(pad "207" smd rect
			(at 4.59994 52.69992 90)
			(size 1.8034 0.508)
			(layers "F.Cu" "F.Mask" "F.Paste")
			(net "M_J_BG<1>")
		)
		(pad "208" smd rect
			(at 4.59994 53.550058 90)
			(size 1.8034 0.508)
			(layers "F.Cu" "F.Mask" "F.Paste")
			(net "M_J_ALERT_N")
		)
		(pad "209" smd rect
			(at 4.59994 54.399942 90)
			(size 1.8034 0.508)
			(layers "F.Cu" "F.Mask" "F.Paste")
			(net "PVDDQ_GHJ")
		)
		(pad "210" smd rect
			(at 4.59994 55.25008 90)
			(size 1.8034 0.508)
			(layers "F.Cu" "F.Mask" "F.Paste")
			(net "M_J_MA<11>")
		)
		(pad "211" smd rect
			(at 4.59994 56.099964 90)
			(size 1.8034 0.508)
			(layers "F.Cu" "F.Mask" "F.Paste")
			(net "M_J_MA<7>")
		)
		(pad "212" smd rect
			(at 4.59994 56.950102 90)
			(size 1.8034 0.508)
			(layers "F.Cu" "F.Mask" "F.Paste")
			(net "PVDDQ_GHJ")
		)
		(pad "213" smd rect
			(at 4.59994 57.799986 90)
			(size 1.8034 0.508)
			(layers "F.Cu" "F.Mask" "F.Paste")
			(net "M_J_MA<5>")
		)
		(pad "214" smd rect
			(at 4.59994 58.650124 90)
			(size 1.8034 0.508)
			(layers "F.Cu" "F.Mask" "F.Paste")
			(net "M_J_MA<4>")
		)
		(pad "215" smd rect
			(at 4.59994 59.500008 90)
			(size 1.8034 0.508)
			(layers "F.Cu" "F.Mask" "F.Paste")
			(net "PVDDQ_GHJ")
		)
		(pad "216" smd rect
			(at 4.59994 60.349892 90)
			(size 1.8034 0.508)
			(layers "F.Cu" "F.Mask" "F.Paste")
			(net "M_J_MA<2>")
		)
		(pad "217" smd rect
			(at 4.59994 61.20003 90)
			(size 1.8034 0.508)
			(layers "F.Cu" "F.Mask" "F.Paste")
			(net "PVDDQ_GHJ")
		)
		(pad "218" smd rect
			(at 4.59994 62.049914 90)
			(size 1.8034 0.508)
			(layers "F.Cu" "F.Mask" "F.Paste")
			(net "M_J_CLK_DP<1>")
		)
		(pad "219" smd rect
			(at 4.59994 62.900052 90)
			(size 1.8034 0.508)
			(layers "F.Cu" "F.Mask" "F.Paste")
			(net "M_J_CLK_DN<1>")
		)
		(pad "220" smd rect
			(at 4.59994 63.749936 90)
			(size 1.8034 0.508)
			(layers "F.Cu" "F.Mask" "F.Paste")
			(net "PVDDQ_GHJ")
		)
		(pad "221" smd rect
			(at 4.59994 64.600074 90)
			(size 1.8034 0.508)
			(layers "F.Cu" "F.Mask" "F.Paste")
			(net "PVTT_GHJ")
		)
		(pad "222" smd rect
			(at 4.59994 70.550024 90)
			(size 1.8034 0.508)
			(layers "F.Cu" "F.Mask" "F.Paste")
			(net "M_J_PAR")
		)
		(pad "223" smd rect
			(at 4.59994 71.399908 90)
			(size 1.8034 0.508)
			(layers "F.Cu" "F.Mask" "F.Paste")
			(net "PVDDQ_GHJ")
		)
		(pad "224" smd rect
			(at 4.59994 72.250046 90)
			(size 1.8034 0.508)
			(layers "F.Cu" "F.Mask" "F.Paste")
			(net "M_J_BA<1>")
		)
		(pad "225" smd rect
			(at 4.59994 73.09993 90)
			(size 1.8034 0.508)
			(layers "F.Cu" "F.Mask" "F.Paste")
			(net "M_J_MA<10>")
		)
		(pad "226" smd rect
			(at 4.59994 73.950068 90)
			(size 1.8034 0.508)
			(layers "F.Cu" "F.Mask" "F.Paste")
			(net "PVDDQ_GHJ")
		)
		(pad "227" smd rect
			(at 4.59994 74.799952 90)
			(size 1.8034 0.508)
			(layers "F.Cu" "F.Mask" "F.Paste")
			(net "TP_CH_J_DIMM_J0_RFU_1")
		)
		(pad "228" smd rect
			(at 4.59994 75.65009 90)
			(size 1.8034 0.508)
			(layers "F.Cu" "F.Mask" "F.Paste")
			(net "M_J_MA<14>")
		)
		(pad "229" smd rect
			(at 4.59994 76.499974 90)
			(size 1.8034 0.508)
			(layers "F.Cu" "F.Mask" "F.Paste")
			(net "PVDDQ_GHJ")
		)
		(pad "230" smd rect
			(at 4.59994 77.350112 90)
			(size 1.8034 0.508)
			(layers "F.Cu" "F.Mask" "F.Paste")
			(net "FM_ADR_COMPLETE_GHJ_N")
		)
		(pad "231" smd rect
			(at 4.59994 78.199996 90)
			(size 1.8034 0.508)
			(layers "F.Cu" "F.Mask" "F.Paste")
			(net "PVDDQ_GHJ")
		)
		(pad "232" smd rect
			(at 4.59994 79.04988 90)
			(size 1.8034 0.508)
			(layers "F.Cu" "F.Mask" "F.Paste")
			(net "M_J_MA<13>")
		)
		(pad "233" smd rect
			(at 4.59994 79.900018 90)
			(size 1.8034 0.508)
			(layers "F.Cu" "F.Mask" "F.Paste")
			(net "PVDDQ_GHJ")
		)
		(pad "234" smd rect
			(at 4.59994 80.749902 90)
			(size 1.8034 0.508)
			(layers "F.Cu" "F.Mask" "F.Paste")
			(net "M_J_MA<17>")
		)
		(pad "235" smd rect
			(at 4.59994 81.60004 90)
			(size 1.8034 0.508)
			(layers "F.Cu" "F.Mask" "F.Paste")
			(net "M_J_C<2>")
		)
		(pad "236" smd rect
			(at 4.59994 82.449924 90)
			(size 1.8034 0.508)
			(layers "F.Cu" "F.Mask" "F.Paste")
			(net "PVDDQ_GHJ")
		)
		(pad "237" smd rect
			(at 4.59994 83.300062 90)
			(size 1.8034 0.508)
			(layers "F.Cu" "F.Mask" "F.Paste")
			(net "M_J_CS_N<3>")
		)
		(pad "238" smd rect
			(at 4.59994 84.149946 90)
			(size 1.8034 0.508)
			(layers "F.Cu" "F.Mask" "F.Paste")
			(net "PVPP_GHJ")
		)
		(pad "239" smd rect
			(at 4.59994 85.000084 90)
			(size 1.8034 0.508)
			(layers "F.Cu" "F.Mask" "F.Paste")
			(net "GND")
		)
		(pad "240" smd rect
			(at 4.59994 85.849968 90)
			(size 1.8034 0.508)
			(layers "F.Cu" "F.Mask" "F.Paste")
			(net "M_J_DQ<36>")
		)
	)
)
